#ISCELL
  mstr_misc dns *
  *
#ISCELL
  pure_quanta quanta_title_block_c *
  *
#ISCELL
  pure_quanta_power cad_note *
  *
#CELL
  pure_quanta q_res *
  page411_i10
#CELL
  pure_quanta q_inductor *
  page411_i11
#CELL
  pure_quanta q_cap *
  page411_i12
#ISCELL
  pure_quanta_power p1v0 *
  page411_i13
#ISCELL
  pure_quanta_power p1v0 *
  page411_i14
#CELL
  pure_quanta q_cap *
  page411_i15
#CELL
  pure_quanta q_cap *
  page411_i16
#CELL
  pure_quanta q_cap *
  page411_i17
#CELL
  pure_quanta q_cap *
  page411_i18
#CELL
  pure_quanta q_cap *
  page411_i19
#CELL
  pure_quanta q_res *
  page411_i2
#CELL
  pure_quanta q_cap *
  page411_i20
#CELL
  pure_quanta q_cap *
  page411_i21
#CELL
  pure_quanta q_cap *
  page411_i22
#ISCELL
  pure_quanta_power universal_gnd *
  page411_i23
#CELL
  pure_quanta q_cap *
  page411_i24
#CELL
  pure_quanta q_cap *
  page411_i25
#CELL
  pure_quanta q_cap *
  page411_i26
#CELL
  pure_quanta q_cap *
  page411_i27
#CELL
  pure_quanta q_cap *
  page411_i28
#ISCELL
  pure_quanta_power vcc_core *
  page411_i29
#ISCELL
  pure_quanta_power vcc_core *
  page411_i30
#ISCELL
  pure_quanta_power universal_gnd *
  page411_i31
#CELL
  pure_quanta q_cap *
  page411_i32
#CELL
  pure_quanta q_cap *
  page411_i34
#CELL
  pure_quanta q_res *
  page411_i36
#CELL
  pure_quanta q_cap *
  page411_i37
#CELL
  pure_quanta q_cap *
  page411_i38
#CELL
  pure_quanta q_cap *
  page411_i39
#CELL
  pure_quanta q_res *
  page411_i4
#CELL
  pure_quanta q_cap *
  page411_i40
#CELL
  pure_quanta q_cap *
  page411_i41
#CELL
  pure_quanta q_cap *
  page411_i42
#CELL
  pure_quanta q_cap *
  page411_i43
#CELL
  pure_quanta q_cap *
  page411_i44
#CELL
  pure_quanta q_cap *
  page411_i45
#CELL
  pure_quanta q_cap *
  page411_i46
#CELL
  pure_quanta q_cap *
  page411_i47
#CELL
  pure_quanta q_cap *
  page411_i48
#CELL
  pure_quanta q_cap *
  page411_i49
#CELL
  pure_quanta q_cap *
  page411_i5
#CELL
  pure_quanta q_cap *
  page411_i50
#CELL
  pure_quanta q_cap *
  page411_i51
#CELL
  pure_quanta q_cap *
  page411_i52
#CELL
  pure_quanta q_cap *
  page411_i53
#ISCELL
  pure_quanta_power universal_gnd *
  page411_i54
#CELL
  pure_quanta q_cap *
  page411_i55
#CELL
  pure_quanta q_cap *
  page411_i58
#CELL
  pure_quanta q_cap *
  page411_i59
#ISCELL
  pure_quanta_power universal_gnd *
  page411_i6
#CELL
  pure_quanta q_cap *
  page411_i61
#ISCELL
  pure_quanta_power universal_gnd *
  page411_i62
#CELL
  pure_quanta q_inductor *
  page411_i63
#CELL
  pure_quanta q_cap *
  page411_i64
#CELL
  pure_quanta q_cap *
  page411_i65
#ISCELL
  pure_quanta_power vcc_core *
  page411_i66
#CELL
  pure_quanta q_cap *
  page411_i67
#CELL
  pure_quanta q_cap *
  page411_i68
#CELL
  pure_quanta q_cap *
  page411_i69
#CELL
  pure_quanta q_cap *
  page411_i7
#CELL
  pure_quanta q_cap *
  page411_i70
#CELL
  pure_quanta q_cap *
  page411_i71
#CELL
  pure_quanta q_cap *
  page411_i72
#CELL
  pure_quanta q_cap *
  page411_i73
#CELL
  pure_quanta q_cap *
  page411_i74
#CELL
  pure_quanta q_cap *
  page411_i75
#CELL
  pure_quanta q_cap *
  page411_i76
#CELL
  pure_quanta q_cap *
  page411_i77
#CELL
  pure_quanta q_cap *
  page411_i78
#CELL
  pure_quanta q_cap *
  page411_i79
#ISCELL
  pure_quanta_power p1v0 *
  page411_i8
#ISCELL
  pure_quanta_power universal_gnd *
  page411_i80
#CELL
  pure_quanta q_cap *
  page411_i81
#CELL
  pure_quanta q_cap *
  page411_i82
#CELL
  pure_quanta q_cap *
  page411_i83
#CELL
  pure_quanta q_cap *
  page411_i84
#CELL
  pure_quanta q_cap *
  page411_i85
#CELL
  pure_quanta q_cap *
  page411_i86
#CELL
  pure_quanta q_cap *
  page411_i87
#CELL
  pure_quanta q_inductor *
  page411_i88
#CELL
  pure_quanta q_res *
  page411_i89
#ISCELL
  pure_quanta_power universal_gnd *
  page411_i9
#CELL
  pure_quanta q_cap *
  page411_i90
#CELL
  pure_quanta q_cap *
  page411_i91
#CELL
  pure_quanta q_cap *
  page411_i92
#CELL
  pure_quanta q_cap *
  page411_i93
#CELL
  pure_quanta q_cap *
  page411_i94
#CELL
  pure_quanta q_capp *
  page411_i95
#CELL
  pure_quanta q_capp *
  page411_i96
#CELL
  pure_quanta q_cap *
  page411_i97
